(kicad_pcb
	(version 20260206)
	(generator "pcbnew")
	(generator_version "10.0")
	(general
		(thickness 1.6)
		(legacy_teardrops no)
	)
	(paper "A4")
	(title_block
		(title "04192023_DAF0TMB3IC0_F0TG_MB_C_brd_V02_OCP.brd")
		(comment 1 "Grand Teton / footprints 3010-3015 of 8354")
	)
	(layers
		(0 "F.Cu" signal "TOP")
		(4 "In1.Cu" signal "GND")
		(6 "In2.Cu" signal "IN1")
		(8 "In3.Cu" signal "GND1")
		(10 "In4.Cu" signal "IN2")
		(12 "In5.Cu" signal "GND2")
		(14 "In6.Cu" signal "IN3")
		(16 "In7.Cu" signal "GND3")
		(18 "In8.Cu" signal "VCC")
		(20 "In9.Cu" signal "VCC1")
		(22 "In10.Cu" signal "GND4")
		(24 "In11.Cu" signal "IN4")
		(26 "In12.Cu" signal "GND5")
		(28 "In13.Cu" signal "IN5")
		(30 "In14.Cu" signal "GND6")
		(32 "In15.Cu" signal "IN6")
		(34 "In16.Cu" signal "GND7")
		(2 "B.Cu" signal "BOTTOM")
		(9 "F.Adhes" user "F.Adhesive")
		(11 "B.Adhes" user "B.Adhesive")
		(13 "F.Paste" user "Package Geometry/Pastemask Top")
		(15 "B.Paste" user "Package Geometry/Pastemask Bottom")
		(5 "F.SilkS" user "Ref Des/Silkscreen Top")
		(7 "B.SilkS" user "Ref Des/Silkscreen Bottom")
		(1 "F.Mask" user "Board Geometry/Soldermask Top")
		(3 "B.Mask" user "Board Geometry/Soldermask Bottom")
		(17 "Dwgs.User" user "User.Drawings")
		(19 "Cmts.User" user "User.Comments")
		(21 "Eco1.User" user "User.Eco1")
		(23 "Eco2.User" user "User.Eco2")
		(25 "Edge.Cuts" user "Board Geometry/Outline")
		(27 "Margin" user)
		(31 "F.CrtYd" user "Package Geometry/Place Bound Top")
		(29 "B.CrtYd" user "Package Geometry/Place Bound Bottom")
		(35 "F.Fab" user "Ref Des/Assembly Top")
		(33 "B.Fab" user "Ref Des/Assembly Bottom")
	)
	(footprint ""
		(layer "F.Cu")
		(at 154.998166 -57.118758)
		(property "Reference" "U264"
			(at 4.994656 -3.027426 0)
			(unlocked yes)
			(layer "F.SilkS")
			(effects
				(font
					(size 0.7874 0.5842)
					(thickness 0.1524)
				)
			)
		)
		(property "Value" ""
			(at 0 0 0)
			(layer "F.Fab")
			(effects
				(font
					(size 1.27 1.27)
				)
			)
		)
		(duplicate_pad_numbers_are_jumpers no)
		(fp_line
			(start -1.500124 -1.500124)
			(end -1.004062 -1.500124)
			(stroke
				(width 0.1524)
				(type default)
			)
			(layer "F.SilkS")
		)
		(fp_line
			(start -1.500124 -1.004062)
			(end -1.500124 -1.500124)
			(stroke
				(width 0.1524)
				(type default)
			)
			(layer "F.SilkS")
		)
		(fp_line
			(start -1.500124 1.500124)
			(end -1.500124 1.004062)
			(stroke
				(width 0.1524)
				(type default)
			)
			(layer "F.SilkS")
		)
		(fp_line
			(start -1.004062 1.500124)
			(end -1.500124 1.500124)
			(stroke
				(width 0.1524)
				(type default)
			)
			(layer "F.SilkS")
		)
		(fp_line
			(start 1.004062 -1.500124)
			(end 1.500124 -1.500124)
			(stroke
				(width 0.1524)
				(type default)
			)
			(layer "F.SilkS")
		)
		(fp_line
			(start 1.500124 -1.500124)
			(end 1.500124 -1.004062)
			(stroke
				(width 0.1524)
				(type default)
			)
			(layer "F.SilkS")
		)
		(fp_line
			(start 1.500124 1.004062)
			(end 1.500124 1.500124)
			(stroke
				(width 0.1524)
				(type default)
			)
			(layer "F.SilkS")
		)
		(fp_line
			(start 1.500124 1.500124)
			(end 1.004062 1.500124)
			(stroke
				(width 0.1524)
				(type default)
			)
			(layer "F.SilkS")
		)
		(fp_poly
			(pts
				(xy -3.570986 -0.960882) (xy -3.08737 -1.854454) (xy -2.435606 -0.924306)
			)
			(stroke
				(width 0)
				(type default)
			)
			(fill yes)
			(layer "F.SilkS")
		)
		(fp_line
			(start -1.500124 -1.500124)
			(end 1.500124 -1.500124)
			(stroke
				(width 0.1)
				(type default)
			)
			(layer "F.Fab")
		)
		(fp_line
			(start -1.500124 1.500124)
			(end -1.500124 -1.500124)
			(stroke
				(width 0.1)
				(type default)
			)
			(layer "F.Fab")
		)
		(fp_line
			(start 1.500124 -1.500124)
			(end 1.500124 1.500124)
			(stroke
				(width 0.1)
				(type default)
			)
			(layer "F.Fab")
		)
		(fp_line
			(start 1.500124 1.500124)
			(end -1.500124 1.500124)
			(stroke
				(width 0.1)
				(type default)
			)
			(layer "F.Fab")
		)
		(fp_poly
			(pts
				(xy -2.847848 -1.258062) (xy -2.847848 -0.242062) (xy -1.831848 -0.750062)
			)
			(stroke
				(width 0)
				(type default)
			)
			(fill yes)
			(layer "F.Fab")
		)
		(pad "1" smd rect
			(at -1.400048 -0.750062 270)
			(size 0.2286 0.6096)
			(layers "F.Cu" "F.Mask" "F.Paste")
			(net "INA230_4_A1")
		)
		(pad "2" smd rect
			(at -1.400048 -0.249936 270)
			(size 0.2286 0.6096)
			(layers "F.Cu" "F.Mask" "F.Paste")
			(net "INA230_4_A0")
		)
		(pad "3" smd rect
			(at -1.400048 0.249936 270)
			(size 0.2286 0.6096)
			(layers "F.Cu" "F.Mask" "F.Paste")
			(net "M2_0_P3V3_ADC_ALERT_R")
		)
		(pad "4" smd rect
			(at -1.400048 0.750062 270)
			(size 0.2286 0.6096)
			(layers "F.Cu" "F.Mask" "F.Paste")
			(net "SMB_INA230_4_3V3AUX_SDA_R1")
		)
		(pad "5" smd rect
			(at -0.750062 1.400048)
			(size 0.2286 0.6096)
			(layers "F.Cu" "F.Mask" "F.Paste")
			(net "SMB_INA230_4_3V3AUX_SCL_R1")
		)
		(pad "6" smd rect
			(at -0.249936 1.400048)
			(size 0.2286 0.6096)
			(layers "F.Cu" "F.Mask" "F.Paste")
			(net "NC_INA230_4_NC0")
		)
		(pad "7" smd rect
			(at 0.249936 1.400048)
			(size 0.2286 0.6096)
			(layers "F.Cu" "F.Mask" "F.Paste")
			(net "NC_INA230_4_NC1")
		)
		(pad "8" smd rect
			(at 0.750062 1.400048)
			(size 0.2286 0.6096)
			(layers "F.Cu" "F.Mask" "F.Paste")
			(net "NC_INA230_4_NC2")
		)
		(pad "9" smd rect
			(at 1.400048 0.750062 270)
			(size 0.2286 0.6096)
			(layers "F.Cu" "F.Mask" "F.Paste")
			(net "P3V3_AUX")
		)
		(pad "10" smd rect
			(at 1.400048 0.249936 270)
			(size 0.2286 0.6096)
			(layers "F.Cu" "F.Mask" "F.Paste")
			(net "GND")
		)
		(pad "11" smd rect
			(at 1.400048 -0.249936 270)
			(size 0.2286 0.6096)
			(layers "F.Cu" "F.Mask" "F.Paste")
			(net "P3V3")
		)
		(pad "12" smd rect
			(at 1.400048 -0.750062 270)
			(size 0.2286 0.6096)
			(layers "F.Cu" "F.Mask" "F.Paste")
			(net "VSENSE_P12V_INA230_4_INN")
		)
		(pad "13" smd rect
			(at 0.750062 -1.400048)
			(size 0.2286 0.6096)
			(layers "F.Cu" "F.Mask" "F.Paste")
			(net "VSENSE_P12V_INA230_4_INP")
		)
		(pad "14" smd rect
			(at 0.249936 -1.400048)
			(size 0.2286 0.6096)
			(layers "F.Cu" "F.Mask" "F.Paste")
			(net "NC_INA230_4_NC3")
		)
		(pad "15" smd rect
			(at -0.249936 -1.400048)
			(size 0.2286 0.6096)
			(layers "F.Cu" "F.Mask" "F.Paste")
			(net "NC_INA230_4_NC4")
		)
		(pad "16" smd rect
			(at -0.750062 -1.400048)
			(size 0.2286 0.6096)
			(layers "F.Cu" "F.Mask" "F.Paste")
			(net "NC_INA230_4_NC5")
		)
		(pad "TH" smd rect
			(at 0 0)
			(size 1.7018 1.7018)
			(layers "F.Cu" "F.Mask" "F.Paste")
			(net "GND")
		)
		(zone
			(layer "F.Cu")
			(hatch none 0.5)
			(connect_pads
				(clearance 0)
			)
			(min_thickness 0.25)
			(keepout
				(tracks not_allowed)
				(vias allowed)
				(pads allowed)
				(copperpour not_allowed)
				(footprints allowed)
			)
			(placement
				(enabled no)
				(sheetname "")
			)
			(fill
				(thermal_gap 0.5)
				(thermal_bridge_width 0.5)
				(island_removal_mode 0)
			)
			(polygon
				(pts
					(xy 153.953718 -57.118758) (xy 154.096466 -57.118758) (xy 154.096466 -56.217058) (xy 155.899866 -56.217058)
					(xy 155.899866 -56.64454) (xy 156.042614 -56.64454) (xy 156.042614 -56.07431) (xy 153.953718 -56.07431)
				)
			)
		)
	)
	(footprint ""
		(layer "F.Cu")
		(at 297.486324 -116.545614 180)
		(property "Reference" "R66"
			(at 0 0 180)
			(layer "F.SilkS")
			(hide yes)
			(effects
				(font
					(size 1.27 1.27)
				)
			)
		)
		(property "Value" ""
			(at 0 0 180)
			(layer "F.Fab")
			(effects
				(font
					(size 1.27 1.27)
				)
			)
		)
		(duplicate_pad_numbers_are_jumpers no)
		(fp_line
			(start 0.7874 0.4064)
			(end -0.7874 0.4064)
			(stroke
				(width 0.1524)
				(type default)
			)
			(layer "F.SilkS")
		)
		(fp_line
			(start 0.7874 -0.4064)
			(end 0.7874 0.4064)
			(stroke
				(width 0.1524)
				(type default)
			)
			(layer "F.SilkS")
		)
		(fp_line
			(start -0.7874 0.4064)
			(end -0.7874 -0.4064)
			(stroke
				(width 0.1524)
				(type default)
			)
			(layer "F.SilkS")
		)
		(fp_line
			(start -0.7874 -0.4064)
			(end 0.7874 -0.4064)
			(stroke
				(width 0.1524)
				(type default)
			)
			(layer "F.SilkS")
		)
		(fp_line
			(start 0.67945 0.3048)
			(end 0.120396 0.3048)
			(stroke
				(width 0.1)
				(type default)
			)
			(layer "F.Fab")
		)
		(fp_line
			(start 0.67945 -0.3048)
			(end 0.67945 0.3048)
			(stroke
				(width 0.1)
				(type default)
			)
			(layer "F.Fab")
		)
		(fp_line
			(start 0.12065 -0.2794)
			(end 0.12065 -0.3048)
			(stroke
				(width 0.1)
				(type default)
			)
			(layer "F.Fab")
		)
		(fp_line
			(start 0.12065 -0.3048)
			(end 0.67945 -0.3048)
			(stroke
				(width 0.1)
				(type default)
			)
			(layer "F.Fab")
		)
		(fp_line
			(start 0.120396 0.3048)
			(end 0.120396 0.2794)
			(stroke
				(width 0.1)
				(type default)
			)
			(layer "F.Fab")
		)
		(fp_line
			(start 0.120396 0.2794)
			(end -0.12065 0.2794)
			(stroke
				(width 0.1)
				(type default)
			)
			(layer "F.Fab")
		)
		(fp_line
			(start -0.12065 0.3048)
			(end -0.67945 0.3048)
			(stroke
				(width 0.1)
				(type default)
			)
			(layer "F.Fab")
		)
		(fp_line
			(start -0.12065 0.2794)
			(end -0.12065 0.3048)
			(stroke
				(width 0.1)
				(type default)
			)
			(layer "F.Fab")
		)
		(fp_line
			(start -0.12065 -0.2794)
			(end 0.12065 -0.2794)
			(stroke
				(width 0.1)
				(type default)
			)
			(layer "F.Fab")
		)
		(fp_line
			(start -0.12065 -0.305054)
			(end -0.12065 -0.2794)
			(stroke
				(width 0.1)
				(type default)
			)
			(layer "F.Fab")
		)
		(fp_line
			(start -0.67945 0.3048)
			(end -0.67945 -0.305054)
			(stroke
				(width 0.1)
				(type default)
			)
			(layer "F.Fab")
		)
		(fp_line
			(start -0.67945 -0.305054)
			(end -0.12065 -0.305054)
			(stroke
				(width 0.1)
				(type default)
			)
			(layer "F.Fab")
		)
		(pad "1" smd circle
			(at -0.40005 0 180)
			(size 0 0)
			(layers "F.Cu" "F.Mask" "F.Paste")
			(net "P3V3_AUX")
		)
		(pad "2" smd circle
			(at 0.40005 0 180)
			(size 0 0)
			(layers "F.Cu" "F.Mask" "F.Paste")
			(net "SMB_FRU_3V3AUX_SCL")
		)
	)
	(footprint ""
		(layer "F.Cu")
		(at 394.067284 -391.0584 180)
		(property "Reference" "R1101"
			(at 0 0 180)
			(layer "F.SilkS")
			(hide yes)
			(effects
				(font
					(size 1.27 1.27)
				)
			)
		)
		(property "Value" ""
			(at 0 0 180)
			(layer "F.Fab")
			(effects
				(font
					(size 1.27 1.27)
				)
			)
		)
		(duplicate_pad_numbers_are_jumpers no)
		(fp_line
			(start 0.32512 0.175006)
			(end -0.32512 0.175006)
			(stroke
				(width 0.1)
				(type default)
			)
			(layer "F.Fab")
		)
		(fp_line
			(start 0.32512 -0.175006)
			(end 0.32512 0.175006)
			(stroke
				(width 0.1)
				(type default)
			)
			(layer "F.Fab")
		)
		(fp_line
			(start -0.32512 0.175006)
			(end -0.32512 -0.175006)
			(stroke
				(width 0.1)
				(type default)
			)
			(layer "F.Fab")
		)
		(fp_line
			(start -0.32512 -0.175006)
			(end 0.32512 -0.175006)
			(stroke
				(width 0.1)
				(type default)
			)
			(layer "F.Fab")
		)
		(pad "1" smd rect
			(at -0.2667 0 180)
			(size 0.3048 0.381)
			(layers "F.Cu" "F.Mask" "F.Paste")
			(net "P1V8_CPU0_RT_1D")
		)
		(pad "2" smd rect
			(at 0.2667 0)
			(size 0.3048 0.381)
			(layers "F.Cu" "F.Mask" "F.Paste")
			(net "RT_CPU0_P3_ADDR1")
		)
	)
	(footprint ""
		(layer "F.Cu")
		(at 440.40171 -14.643354 180)
		(property "Reference" "C1236"
			(at 0 0 180)
			(layer "F.SilkS")
			(hide yes)
			(effects
				(font
					(size 1.27 1.27)
				)
			)
		)
		(property "Value" ""
			(at 0 0 180)
			(layer "F.Fab")
			(effects
				(font
					(size 1.27 1.27)
				)
			)
		)
		(duplicate_pad_numbers_are_jumpers no)
		(fp_line
			(start 0.7874 0.4064)
			(end -0.7874 0.4064)
			(stroke
				(width 0.1524)
				(type default)
			)
			(layer "F.SilkS")
		)
		(fp_line
			(start 0.7874 -0.4064)
			(end 0.7874 0.4064)
			(stroke
				(width 0.1524)
				(type default)
			)
			(layer "F.SilkS")
		)
		(fp_line
			(start -0.7874 0.4064)
			(end -0.7874 -0.4064)
			(stroke
				(width 0.1524)
				(type default)
			)
			(layer "F.SilkS")
		)
		(fp_line
			(start -0.7874 -0.4064)
			(end 0.7874 -0.4064)
			(stroke
				(width 0.1524)
				(type default)
			)
			(layer "F.SilkS")
		)
		(fp_line
			(start 0.67945 0.3048)
			(end 0.120396 0.3048)
			(stroke
				(width 0.1)
				(type default)
			)
			(layer "F.Fab")
		)
		(fp_line
			(start 0.67945 -0.3048)
			(end 0.67945 0.3048)
			(stroke
				(width 0.1)
				(type default)
			)
			(layer "F.Fab")
		)
		(fp_line
			(start 0.12065 -0.2794)
			(end 0.12065 -0.3048)
			(stroke
				(width 0.1)
				(type default)
			)
			(layer "F.Fab")
		)
		(fp_line
			(start 0.12065 -0.3048)
			(end 0.67945 -0.3048)
			(stroke
				(width 0.1)
				(type default)
			)
			(layer "F.Fab")
		)
		(fp_line
			(start 0.120396 0.3048)
			(end 0.120396 0.2794)
			(stroke
				(width 0.1)
				(type default)
			)
			(layer "F.Fab")
		)
		(fp_line
			(start 0.120396 0.2794)
			(end -0.12065 0.2794)
			(stroke
				(width 0.1)
				(type default)
			)
			(layer "F.Fab")
		)
		(fp_line
			(start -0.12065 0.3048)
			(end -0.67945 0.3048)
			(stroke
				(width 0.1)
				(type default)
			)
			(layer "F.Fab")
		)
		(fp_line
			(start -0.12065 0.2794)
			(end -0.12065 0.3048)
			(stroke
				(width 0.1)
				(type default)
			)
			(layer "F.Fab")
		)
		(fp_line
			(start -0.12065 -0.2794)
			(end 0.12065 -0.2794)
			(stroke
				(width 0.1)
				(type default)
			)
			(layer "F.Fab")
		)
		(fp_line
			(start -0.12065 -0.305054)
			(end -0.12065 -0.2794)
			(stroke
				(width 0.1)
				(type default)
			)
			(layer "F.Fab")
		)
		(fp_line
			(start -0.67945 0.3048)
			(end -0.67945 -0.305054)
			(stroke
				(width 0.1)
				(type default)
			)
			(layer "F.Fab")
		)
		(fp_line
			(start -0.67945 -0.305054)
			(end -0.12065 -0.305054)
			(stroke
				(width 0.1)
				(type default)
			)
			(layer "F.Fab")
		)
		(pad "1" smd circle
			(at -0.40005 0 180)
			(size 0 0)
			(layers "F.Cu" "F.Mask" "F.Paste")
			(net "P12V_OCP_SFF_R")
		)
		(pad "2" smd circle
			(at 0.40005 0 180)
			(size 0 0)
			(layers "F.Cu" "F.Mask" "F.Paste")
			(net "GND")
		)
	)
	(footprint ""
		(layer "F.Cu")
		(at 183.769 -92.674948 90)
		(property "Reference" "R6074"
			(at 0 0 90)
			(layer "F.SilkS")
			(hide yes)
			(effects
				(font
					(size 1.27 1.27)
				)
			)
		)
		(property "Value" ""
			(at 0 0 90)
			(layer "F.Fab")
			(effects
				(font
					(size 1.27 1.27)
				)
			)
		)
		(duplicate_pad_numbers_are_jumpers no)
		(fp_line
			(start 0.7874 -0.4064)
			(end 0.7874 0.4064)
			(stroke
				(width 0.1524)
				(type default)
			)
			(layer "F.SilkS")
		)
		(fp_line
			(start -0.7874 -0.4064)
			(end 0.7874 -0.4064)
			(stroke
				(width 0.1524)
				(type default)
			)
			(layer "F.SilkS")
		)
		(fp_line
			(start 0.7874 0.4064)
			(end -0.7874 0.4064)
			(stroke
				(width 0.1524)
				(type default)
			)
			(layer "F.SilkS")
		)
		(fp_line
			(start -0.7874 0.4064)
			(end -0.7874 -0.4064)
			(stroke
				(width 0.1524)
				(type default)
			)
			(layer "F.SilkS")
		)
		(fp_line
			(start -0.12065 -0.305054)
			(end -0.12065 -0.2794)
			(stroke
				(width 0.1)
				(type default)
			)
			(layer "F.Fab")
		)
		(fp_line
			(start -0.67945 -0.305054)
			(end -0.12065 -0.305054)
			(stroke
				(width 0.1)
				(type default)
			)
			(layer "F.Fab")
		)
		(fp_line
			(start 0.67945 -0.3048)
			(end 0.67945 0.3048)
			(stroke
				(width 0.1)
				(type default)
			)
			(layer "F.Fab")
		)
		(fp_line
			(start 0.12065 -0.3048)
			(end 0.67945 -0.3048)
			(stroke
				(width 0.1)
				(type default)
			)
			(layer "F.Fab")
		)
		(fp_line
			(start 0.12065 -0.2794)
			(end 0.12065 -0.3048)
			(stroke
				(width 0.1)
				(type default)
			)
			(layer "F.Fab")
		)
		(fp_line
			(start -0.12065 -0.2794)
			(end 0.12065 -0.2794)
			(stroke
				(width 0.1)
				(type default)
			)
			(layer "F.Fab")
		)
		(fp_line
			(start 0.120396 0.2794)
			(end -0.12065 0.2794)
			(stroke
				(width 0.1)
				(type default)
			)
			(layer "F.Fab")
		)
		(fp_line
			(start -0.12065 0.2794)
			(end -0.12065 0.3048)
			(stroke
				(width 0.1)
				(type default)
			)
			(layer "F.Fab")
		)
		(fp_line
			(start 0.67945 0.3048)
			(end 0.120396 0.3048)
			(stroke
				(width 0.1)
				(type default)
			)
			(layer "F.Fab")
		)
		(fp_line
			(start 0.120396 0.3048)
			(end 0.120396 0.2794)
			(stroke
				(width 0.1)
				(type default)
			)
			(layer "F.Fab")
		)
		(fp_line
			(start -0.12065 0.3048)
			(end -0.67945 0.3048)
			(stroke
				(width 0.1)
				(type default)
			)
			(layer "F.Fab")
		)
		(fp_line
			(start -0.67945 0.3048)
			(end -0.67945 -0.305054)
			(stroke
				(width 0.1)
				(type default)
			)
			(layer "F.Fab")
		)
		(pad "1" smd circle
			(at -0.40005 0 90)
			(size 0 0)
			(layers "F.Cu" "F.Mask" "F.Paste")
			(net "FM_THERMAL_ALERT_N")
		)
		(pad "2" smd circle
			(at 0.40005 0 90)
			(size 0 0)
			(layers "F.Cu" "F.Mask" "F.Paste")
			(net "FM_THERMAL_ALERT_R_N")
		)
	)
	(footprint ""
		(layer "F.Cu")
		(at 403.961346 -142.871952 -90)
		(property "Reference" "C57"
			(at 0 0 270)
			(layer "F.SilkS")
			(hide yes)
			(effects
				(font
					(size 1.27 1.27)
				)
			)
		)
		(property "Value" ""
			(at 0 0 270)
			(layer "F.Fab")
			(effects
				(font
					(size 1.27 1.27)
				)
			)
		)
		(duplicate_pad_numbers_are_jumpers no)
		(fp_line
			(start -1.524 0.762)
			(end -1.524 -0.762)
			(stroke
				(width 0.1524)
				(type default)
			)
			(layer "F.SilkS")
		)
		(fp_line
			(start 1.524 0.762)
			(end -1.524 0.762)
			(stroke
				(width 0.1524)
				(type default)
			)
			(layer "F.SilkS")
		)
		(fp_line
			(start -1.524 -0.762)
			(end 1.524 -0.762)
			(stroke
				(width 0.1524)
				(type default)
			)
			(layer "F.SilkS")
		)
		(fp_line
			(start 1.524 -0.762)
			(end 1.524 0.762)
			(stroke
				(width 0.1524)
				(type default)
			)
			(layer "F.SilkS")
		)
		(fp_line
			(start -1.1049 0.724916)
			(end 1.1049 0.724916)
			(stroke
				(width 0.1)
				(type default)
			)
			(layer "F.Fab")
		)
		(fp_line
			(start 1.1049 0.724916)
			(end 1.1049 -0.724916)
			(stroke
				(width 0.1)
				(type default)
			)
			(layer "F.Fab")
		)
		(fp_line
			(start -1.1049 -0.724916)
			(end -1.1049 0.724916)
			(stroke
				(width 0.1)
				(type default)
			)
			(layer "F.Fab")
		)
		(fp_line
			(start 1.1049 -0.724916)
			(end -1.1049 -0.724916)
			(stroke
				(width 0.1)
				(type default)
			)
			(layer "F.Fab")
		)
		(pad "1" smd rect
			(at -0.889 0 90)
			(size 1.016 1.27)
			(layers "F.Cu" "F.Mask" "F.Paste")
			(net "P5V_AUX")
		)
		(pad "2" smd rect
			(at 0.889 0 90)
			(size 1.016 1.27)
			(layers "F.Cu" "F.Mask" "F.Paste")
			(net "GND")
		)
	)
)
